(kicad_pcb
	(version 20260206)
	(generator "pcbnew")
	(generator_version "10.0")
	(general
		(thickness 1.6)
		(legacy_teardrops no)
	)
	(paper "A4")
	(title_block
		(title "Bryce Canyon_IOM_IOC_16318-2_OCP.brd")
		(comment 1 "Bryce Canyon / footprints 36-43 of 1605")
	)
	(layers
		(0 "F.Cu" signal "TOP")
		(4 "In1.Cu" signal "L2GND")
		(6 "In2.Cu" signal "L3")
		(8 "In3.Cu" signal "L4VCC")
		(10 "In4.Cu" signal "L5VCC")
		(12 "In5.Cu" signal "L6")
		(14 "In6.Cu" signal "L7GND")
		(2 "B.Cu" signal "BOTTOM")
		(9 "F.Adhes" user "F.Adhesive")
		(11 "B.Adhes" user "B.Adhesive")
		(13 "F.Paste" user "Package Geometry/Pastemask Top")
		(15 "B.Paste" user "Package Geometry/Pastemask Bottom")
		(5 "F.SilkS" user "Ref Des/Silkscreen Top")
		(7 "B.SilkS" user "Ref Des/Silkscreen Bottom")
		(1 "F.Mask" user "Board Geometry/Soldermask Top")
		(3 "B.Mask" user "Board Geometry/Soldermask Bottom")
		(17 "Dwgs.User" user "User.Drawings")
		(19 "Cmts.User" user "User.Comments")
		(21 "Eco1.User" user "User.Eco1")
		(23 "Eco2.User" user "User.Eco2")
		(25 "Edge.Cuts" user "Board Geometry/Outline")
		(27 "Margin" user)
		(31 "F.CrtYd" user "Package Geometry/Place Bound Top")
		(29 "B.CrtYd" user "Package Geometry/Place Bound Bottom")
		(35 "F.Fab" user "Ref Des/Assembly Top")
		(33 "B.Fab" user "Ref Des/Assembly Bottom")
	)
	(footprint ""
		(layer "F.Cu")
		(at 157.099 -118.618 -90)
		(property "Reference" "C214"
			(at 0 0 270)
			(layer "F.SilkS")
			(hide yes)
			(effects
				(font
					(size 1.27 1.27)
				)
			)
		)
		(property "Value" "SCD1U16V2KX-3GP"
			(at 1.1811 -2.7051 270)
			(unlocked yes)
			(layer "F.Fab")
			(hide yes)
			(effects
				(font
					(size 1.016 1.016)
					(thickness 0.1524)
				)
			)
		)
		(property "Device Type" "C402H22"
			(at 1.1811 -4.2291 270)
			(unlocked yes)
			(layer "F.Fab")
			(hide yes)
			(effects
				(font
					(size 1.016 1.016)
					(thickness 0.1524)
				)
			)
		)
		(duplicate_pad_numbers_are_jumpers no)
		(fp_rect
			(start -0.4318 0.9525)
			(end 0.4318 -0.9525)
			(stroke
				(width 0)
				(type default)
			)
			(fill no)
			(layer "F.CrtYd")
		)
		(fp_rect
			(start -0.4318 0.9525)
			(end 0.4318 -0.9525)
			(stroke
				(width 0)
				(type default)
			)
			(fill no)
			(layer "F.Fab")
		)
		(pad "1" smd custom
			(at 0 -0.4445 270)
			(size 0.1524 0.1524)
			(layers "F.Cu" "F.Mask" "F.Paste")
			(net "P1V8_STBY")
			(options
				(clearance outline)
				(anchor circle)
			)
			(primitives
				(gr_poly
					(pts
						(arc
							(start 0.3048 -0.2032)
							(mid 0.275042 -0.275042)
							(end 0.2032 -0.3048)
						)
						(arc
							(start -0.2032 -0.3048)
							(mid -0.275042 -0.275042)
							(end -0.3048 -0.2032)
						)
						(arc
							(start -0.3048 0.2032)
							(mid -0.275042 0.275042)
							(end -0.2032 0.3048)
						)
						(arc
							(start 0.2032 0.3048)
							(mid 0.275042 0.275042)
							(end 0.3048 0.2032)
						)
					)
					(width 0)
					(fill yes)
				)
			)
		)
		(pad "2" smd custom
			(at 0 0.4445 270)
			(size 0.1524 0.1524)
			(layers "F.Cu" "F.Mask" "F.Paste")
			(net "GND")
			(options
				(clearance outline)
				(anchor circle)
			)
			(primitives
				(gr_poly
					(pts
						(arc
							(start 0.3048 -0.2032)
							(mid 0.275042 -0.275042)
							(end 0.2032 -0.3048)
						)
						(arc
							(start -0.2032 -0.3048)
							(mid -0.275042 -0.275042)
							(end -0.3048 -0.2032)
						)
						(arc
							(start -0.3048 0.2032)
							(mid -0.275042 0.275042)
							(end -0.2032 0.3048)
						)
						(arc
							(start 0.2032 0.3048)
							(mid 0.275042 0.275042)
							(end 0.3048 0.2032)
						)
					)
					(width 0)
					(fill yes)
				)
			)
		)
	)
	(footprint ""
		(layer "F.Cu")
		(at 179.4002 -81.2546)
		(property "Reference" "TP147"
			(at 0 0 0)
			(layer "F.SilkS")
			(hide yes)
			(effects
				(font
					(size 1.27 1.27)
				)
			)
		)
		(property "Value" "TPAD28-2-GP"
			(at -0.0127 -1.6637 0)
			(unlocked yes)
			(layer "F.Fab")
			(hide yes)
			(effects
				(font
					(size 1.016 1.016)
					(thickness 0.1524)
				)
			)
		)
		(property "Device Type" "TPAD28"
			(at -0.0127 -3.1877 0)
			(unlocked yes)
			(layer "F.Fab")
			(hide yes)
			(effects
				(font
					(size 1.016 1.016)
					(thickness 0.1524)
				)
			)
		)
		(duplicate_pad_numbers_are_jumpers no)
		(fp_poly
			(pts
				(arc
					(start 0.3556 0)
					(mid -0.3556 0)
					(end 0.3556 0)
				)
			)
			(stroke
				(width 0)
				(type default)
			)
			(fill no)
			(layer "F.CrtYd")
		)
		(fp_poly
			(pts
				(arc
					(start 0.6096 0)
					(mid -0.6096 0)
					(end 0.6096 0)
				)
			)
			(stroke
				(width 0)
				(type default)
			)
			(fill no)
			(layer "F.Fab")
		)
		(pad "1" smd circle
			(at 0 0)
			(size 0.7112 0.7112)
			(layers "F.Cu" "F.Mask" "F.Paste")
			(net "SYS_HALT1#")
		)
	)
	(footprint ""
		(layer "F.Cu")
		(at 159.55264 -142.885922 180)
		(property "Reference" "C209"
			(at 0 0 180)
			(layer "F.SilkS")
			(hide yes)
			(effects
				(font
					(size 1.27 1.27)
				)
			)
		)
		(property "Value" "SC1U16V3KX-5GP"
			(at 0 -2.8194 180)
			(unlocked yes)
			(layer "F.Fab")
			(hide yes)
			(effects
				(font
					(size 1.016 1.016)
					(thickness 0.1524)
				)
			)
		)
		(property "Device Type" "C603H36"
			(at 0 -4.3434 180)
			(unlocked yes)
			(layer "F.Fab")
			(hide yes)
			(effects
				(font
					(size 1.016 1.016)
					(thickness 0.1524)
				)
			)
		)
		(duplicate_pad_numbers_are_jumpers no)
		(fp_line
			(start 0.508 0)
			(end -0.508 0)
			(stroke
				(width 0.2032)
				(type default)
			)
			(layer "F.SilkS")
		)
		(fp_rect
			(start -0.5842 1.3335)
			(end 0.5842 -1.3335)
			(stroke
				(width 0)
				(type default)
			)
			(fill no)
			(layer "F.CrtYd")
		)
		(fp_rect
			(start -0.5842 1.3335)
			(end 0.5842 -1.3335)
			(stroke
				(width 0)
				(type default)
			)
			(fill no)
			(layer "F.Fab")
		)
		(pad "1" smd custom
			(at 0 -0.762 180)
			(size 0.2159 0.2159)
			(layers "F.Cu" "F.Mask" "F.Paste")
			(net "P1V8_STBY_VRG5")
			(options
				(clearance outline)
				(anchor circle)
			)
			(primitives
				(gr_poly
					(pts
						(arc
							(start -0.3302 -0.4318)
							(mid -0.402042 -0.402042)
							(end -0.4318 -0.3302)
						)
						(arc
							(start -0.4318 0.3302)
							(mid -0.402042 0.402042)
							(end -0.3302 0.4318)
						)
						(arc
							(start 0.3302 0.4318)
							(mid 0.402042 0.402042)
							(end 0.4318 0.3302)
						)
						(arc
							(start 0.4318 -0.3302)
							(mid 0.402042 -0.402042)
							(end 0.3302 -0.4318)
						)
					)
					(width 0)
					(fill yes)
				)
			)
		)
		(pad "2" smd custom
			(at 0 0.762 180)
			(size 0.2159 0.2159)
			(layers "F.Cu" "F.Mask" "F.Paste")
			(net "GND")
			(options
				(clearance outline)
				(anchor circle)
			)
			(primitives
				(gr_poly
					(pts
						(arc
							(start -0.3302 -0.4318)
							(mid -0.402042 -0.402042)
							(end -0.4318 -0.3302)
						)
						(arc
							(start -0.4318 0.3302)
							(mid -0.402042 0.402042)
							(end -0.3302 0.4318)
						)
						(arc
							(start 0.3302 0.4318)
							(mid 0.402042 0.402042)
							(end 0.4318 0.3302)
						)
						(arc
							(start 0.4318 -0.3302)
							(mid 0.402042 -0.402042)
							(end 0.3302 -0.4318)
						)
					)
					(width 0)
					(fill yes)
				)
			)
		)
	)
	(footprint ""
		(layer "F.Cu")
		(at 185.7756 -90.8558 180)
		(property "Reference" "R659"
			(at 0 0 180)
			(layer "F.SilkS")
			(hide yes)
			(effects
				(font
					(size 1.27 1.27)
				)
			)
		)
		(property "Value" "4K7R2F-GP"
			(at 0.064008 -3.993896 180)
			(unlocked yes)
			(layer "F.Fab")
			(hide yes)
			(effects
				(font
					(size 1.016 1.016)
					(thickness 0.1524)
				)
			)
		)
		(property "Device Type" "R402H16"
			(at 0.064008 -5.517896 180)
			(unlocked yes)
			(layer "F.Fab")
			(hide yes)
			(effects
				(font
					(size 1.016 1.016)
					(thickness 0.1524)
				)
			)
		)
		(duplicate_pad_numbers_are_jumpers no)
		(fp_line
			(start 0.508 -0.9398)
			(end -0.508 -0.9398)
			(stroke
				(width 0.1524)
				(type default)
			)
			(layer "F.SilkS")
		)
		(fp_line
			(start -0.508 -0.9398)
			(end -0.508 0.9398)
			(stroke
				(width 0.1524)
				(type default)
			)
			(layer "F.SilkS")
		)
		(fp_rect
			(start -0.508 0.9398)
			(end 0.508 -0.9398)
			(stroke
				(width 0)
				(type default)
			)
			(fill no)
			(layer "F.CrtYd")
		)
		(fp_rect
			(start -0.508 0.9398)
			(end 0.508 -0.9398)
			(stroke
				(width 0)
				(type default)
			)
			(fill no)
			(layer "F.Fab")
		)
		(pad "1" smd custom
			(at 0 -0.4445 180)
			(size 0.1397 0.1397)
			(layers "F.Cu" "F.Mask" "F.Paste")
			(net "SYS_DBMODE4")
			(options
				(clearance outline)
				(anchor circle)
			)
			(primitives
				(gr_poly
					(pts
						(arc
							(start -0.1778 -0.2794)
							(mid -0.249642 -0.249642)
							(end -0.2794 -0.1778)
						)
						(arc
							(start -0.2794 0.1778)
							(mid -0.249642 0.249642)
							(end -0.1778 0.2794)
						)
						(arc
							(start 0.1778 0.2794)
							(mid 0.249642 0.249642)
							(end 0.2794 0.1778)
						)
						(arc
							(start 0.2794 -0.1778)
							(mid 0.249642 -0.249642)
							(end 0.1778 -0.2794)
						)
					)
					(width 0)
					(fill yes)
				)
			)
		)
		(pad "2" smd custom
			(at 0 0.4445 180)
			(size 0.1397 0.1397)
			(layers "F.Cu" "F.Mask" "F.Paste")
			(net "GND")
			(options
				(clearance outline)
				(anchor circle)
			)
			(primitives
				(gr_poly
					(pts
						(arc
							(start -0.1778 -0.2794)
							(mid -0.249642 -0.249642)
							(end -0.2794 -0.1778)
						)
						(arc
							(start -0.2794 0.1778)
							(mid -0.249642 0.249642)
							(end -0.1778 0.2794)
						)
						(arc
							(start 0.1778 0.2794)
							(mid 0.249642 0.249642)
							(end 0.2794 0.1778)
						)
						(arc
							(start 0.2794 -0.1778)
							(mid 0.249642 -0.249642)
							(end 0.1778 -0.2794)
						)
					)
					(width 0)
					(fill yes)
				)
			)
		)
	)
	(footprint ""
		(layer "F.Cu")
		(at 162.8394 -141.605 -90)
		(property "Reference" "C206"
			(at 0 0 270)
			(layer "F.SilkS")
			(hide yes)
			(effects
				(font
					(size 1.27 1.27)
				)
			)
		)
		(property "Value" "SC100P50V2JN-3GP"
			(at 1.1811 -2.7051 270)
			(unlocked yes)
			(layer "F.Fab")
			(hide yes)
			(effects
				(font
					(size 1.016 1.016)
					(thickness 0.1524)
				)
			)
		)
		(property "Device Type" "C402H22"
			(at 1.1811 -4.2291 270)
			(unlocked yes)
			(layer "F.Fab")
			(hide yes)
			(effects
				(font
					(size 1.016 1.016)
					(thickness 0.1524)
				)
			)
		)
		(duplicate_pad_numbers_are_jumpers no)
		(fp_rect
			(start -0.4318 0.9525)
			(end 0.4318 -0.9525)
			(stroke
				(width 0)
				(type default)
			)
			(fill no)
			(layer "F.CrtYd")
		)
		(fp_rect
			(start -0.4318 0.9525)
			(end 0.4318 -0.9525)
			(stroke
				(width 0)
				(type default)
			)
			(fill no)
			(layer "F.Fab")
		)
		(pad "1" smd custom
			(at 0 -0.4445 270)
			(size 0.1524 0.1524)
			(layers "F.Cu" "F.Mask" "F.Paste")
			(net "P1V8_STBY_CC_R")
			(options
				(clearance outline)
				(anchor circle)
			)
			(primitives
				(gr_poly
					(pts
						(arc
							(start 0.3048 -0.2032)
							(mid 0.275042 -0.275042)
							(end 0.2032 -0.3048)
						)
						(arc
							(start -0.2032 -0.3048)
							(mid -0.275042 -0.275042)
							(end -0.3048 -0.2032)
						)
						(arc
							(start -0.3048 0.2032)
							(mid -0.275042 0.275042)
							(end -0.2032 0.3048)
						)
						(arc
							(start 0.2032 0.3048)
							(mid 0.275042 0.275042)
							(end 0.3048 0.2032)
						)
					)
					(width 0)
					(fill yes)
				)
			)
		)
		(pad "2" smd custom
			(at 0 0.4445 270)
			(size 0.1524 0.1524)
			(layers "F.Cu" "F.Mask" "F.Paste")
			(net "P1V8_STBY_VFB")
			(options
				(clearance outline)
				(anchor circle)
			)
			(primitives
				(gr_poly
					(pts
						(arc
							(start 0.3048 -0.2032)
							(mid 0.275042 -0.275042)
							(end 0.2032 -0.3048)
						)
						(arc
							(start -0.2032 -0.3048)
							(mid -0.275042 -0.275042)
							(end -0.3048 -0.2032)
						)
						(arc
							(start -0.3048 0.2032)
							(mid -0.275042 0.275042)
							(end -0.2032 0.3048)
						)
						(arc
							(start 0.2032 0.3048)
							(mid 0.275042 0.275042)
							(end 0.3048 0.2032)
						)
					)
					(width 0)
					(fill yes)
				)
			)
		)
	)
	(footprint ""
		(layer "F.Cu")
		(at 208.055972 -70.0024 90)
		(property "Reference" "C315"
			(at 0 0 90)
			(layer "F.SilkS")
			(hide yes)
			(effects
				(font
					(size 1.27 1.27)
				)
			)
		)
		(property "Value" "SCD01U16V1KX-GP"
			(at -2.8321 -1.7399 90)
			(unlocked yes)
			(layer "F.Fab")
			(hide yes)
			(effects
				(font
					(size 1.016 1.016)
					(thickness 0.1524)
				)
			)
		)
		(property "Device Type" "C0201H13"
			(at -2.8321 -3.2639 90)
			(unlocked yes)
			(layer "F.Fab")
			(hide yes)
			(effects
				(font
					(size 1.016 1.016)
					(thickness 0.1524)
				)
			)
		)
		(duplicate_pad_numbers_are_jumpers no)
		(fp_rect
			(start -0.2794 0.6477)
			(end 0.2794 -0.6477)
			(stroke
				(width 0)
				(type default)
			)
			(fill no)
			(layer "F.CrtYd")
		)
		(fp_rect
			(start -0.2794 0.6477)
			(end 0.2794 -0.6477)
			(stroke
				(width 0)
				(type default)
			)
			(fill no)
			(layer "F.Fab")
		)
		(pad "1" smd custom
			(at 0 -0.2794 90)
			(size 0.0762 0.0762)
			(layers "F.Cu" "F.Mask" "F.Paste")
			(net "PHY_IOC_TO_CON_B_0_DP_C")
			(options
				(clearance outline)
				(anchor circle)
			)
			(primitives
				(gr_poly
					(pts
						(arc
							(start 0.1524 -0.127)
							(mid 0.137521 -0.162921)
							(end 0.1016 -0.1778)
						)
						(arc
							(start -0.1016 -0.1778)
							(mid -0.137521 -0.162921)
							(end -0.1524 -0.127)
						)
						(arc
							(start -0.1524 0.127)
							(mid -0.137521 0.162921)
							(end -0.1016 0.1778)
						)
						(arc
							(start 0.1016 0.1778)
							(mid 0.137521 0.162921)
							(end 0.1524 0.127)
						)
					)
					(width 0)
					(fill yes)
				)
			)
		)
		(pad "2" smd custom
			(at 0 0.2794 90)
			(size 0.0762 0.0762)
			(layers "F.Cu" "F.Mask" "F.Paste")
			(net "PHY_IOC_TO_CON_B_0_DP")
			(options
				(clearance outline)
				(anchor circle)
			)
			(primitives
				(gr_poly
					(pts
						(arc
							(start 0.1524 -0.127)
							(mid 0.137521 -0.162921)
							(end 0.1016 -0.1778)
						)
						(arc
							(start -0.1016 -0.1778)
							(mid -0.137521 -0.162921)
							(end -0.1524 -0.127)
						)
						(arc
							(start -0.1524 0.127)
							(mid -0.137521 0.162921)
							(end -0.1016 0.1778)
						)
						(arc
							(start 0.1016 0.1778)
							(mid 0.137521 0.162921)
							(end 0.1524 0.127)
						)
					)
					(width 0)
					(fill yes)
				)
			)
		)
	)
	(footprint ""
		(layer "F.Cu")
		(at 198.247 -48.387)
		(property "Reference" "TP138"
			(at 0 0 0)
			(layer "F.SilkS")
			(hide yes)
			(effects
				(font
					(size 1.27 1.27)
				)
			)
		)
		(property "Value" "TPAD28-2-GP"
			(at -0.0127 -1.6637 0)
			(unlocked yes)
			(layer "F.Fab")
			(hide yes)
			(effects
				(font
					(size 1.016 1.016)
					(thickness 0.1524)
				)
			)
		)
		(property "Device Type" "TPAD28"
			(at -0.0127 -3.1877 0)
			(unlocked yes)
			(layer "F.Fab")
			(hide yes)
			(effects
				(font
					(size 1.016 1.016)
					(thickness 0.1524)
				)
			)
		)
		(duplicate_pad_numbers_are_jumpers no)
		(fp_poly
			(pts
				(arc
					(start 0.3556 0)
					(mid -0.3556 0)
					(end 0.3556 0)
				)
			)
			(stroke
				(width 0)
				(type default)
			)
			(fill no)
			(layer "F.CrtYd")
		)
		(fp_poly
			(pts
				(arc
					(start 0.6096 0)
					(mid -0.6096 0)
					(end 0.6096 0)
				)
			)
			(stroke
				(width 0)
				(type default)
			)
			(fill no)
			(layer "F.Fab")
		)
		(pad "1" smd circle
			(at 0 0)
			(size 0.7112 0.7112)
			(layers "F.Cu" "F.Mask" "F.Paste")
			(net "ICE0_TDO")
		)
	)
	(footprint ""
		(layer "F.Cu")
		(at 199.200516 -130.6449 90)
		(property "Reference" "R549"
			(at 0 0 90)
			(layer "F.SilkS")
			(hide yes)
			(effects
				(font
					(size 1.27 1.27)
				)
			)
		)
		(property "Value" "0R2J-2-GP"
			(at 0.064008 -3.993896 90)
			(unlocked yes)
			(layer "F.Fab")
			(hide yes)
			(effects
				(font
					(size 1.016 1.016)
					(thickness 0.1524)
				)
			)
		)
		(property "Device Type" "R402H16"
			(at 0.064008 -5.517896 90)
			(unlocked yes)
			(layer "F.Fab")
			(hide yes)
			(effects
				(font
					(size 1.016 1.016)
					(thickness 0.1524)
				)
			)
		)
		(duplicate_pad_numbers_are_jumpers no)
		(fp_line
			(start 0.508 -0.9398)
			(end -0.508 -0.9398)
			(stroke
				(width 0.1524)
				(type default)
			)
			(layer "F.SilkS")
		)
		(fp_line
			(start -0.508 -0.9398)
			(end -0.508 0.9398)
			(stroke
				(width 0.1524)
				(type default)
			)
			(layer "F.SilkS")
		)
		(fp_rect
			(start -0.508 0.9398)
			(end 0.508 -0.9398)
			(stroke
				(width 0)
				(type default)
			)
			(fill no)
			(layer "F.CrtYd")
		)
		(fp_rect
			(start -0.508 0.9398)
			(end 0.508 -0.9398)
			(stroke
				(width 0)
				(type default)
			)
			(fill no)
			(layer "F.Fab")
		)
		(pad "1" smd custom
			(at 0 -0.4445 90)
			(size 0.1397 0.1397)
			(layers "F.Cu" "F.Mask" "F.Paste")
			(net "PWRGD_P1V8")
			(options
				(clearance outline)
				(anchor circle)
			)
			(primitives
				(gr_poly
					(pts
						(arc
							(start -0.1778 -0.2794)
							(mid -0.249642 -0.249642)
							(end -0.2794 -0.1778)
						)
						(arc
							(start -0.2794 0.1778)
							(mid -0.249642 0.249642)
							(end -0.1778 0.2794)
						)
						(arc
							(start 0.1778 0.2794)
							(mid 0.249642 0.249642)
							(end 0.2794 0.1778)
						)
						(arc
							(start 0.2794 -0.1778)
							(mid 0.249642 -0.249642)
							(end 0.1778 -0.2794)
						)
					)
					(width 0)
					(fill yes)
				)
			)
		)
		(pad "2" smd custom
			(at 0 0.4445 90)
			(size 0.1397 0.1397)
			(layers "F.Cu" "F.Mask" "F.Paste")
			(net "TPS74801_1V5_EN")
			(options
				(clearance outline)
				(anchor circle)
			)
			(primitives
				(gr_poly
					(pts
						(arc
							(start -0.1778 -0.2794)
							(mid -0.249642 -0.249642)
							(end -0.2794 -0.1778)
						)
						(arc
							(start -0.2794 0.1778)
							(mid -0.249642 0.249642)
							(end -0.1778 0.2794)
						)
						(arc
							(start 0.1778 0.2794)
							(mid 0.249642 0.249642)
							(end 0.2794 0.1778)
						)
						(arc
							(start 0.2794 -0.1778)
							(mid 0.249642 -0.249642)
							(end 0.1778 -0.2794)
						)
					)
					(width 0)
					(fill yes)
				)
			)
		)
	)
)
